FILE_TYPE = MULTI_PHYS_TABLE;

PART 'ZENER_AC'

{========================================================================================}
:VALUE             | PART_TYPE | MATERIAL | PART_NUMBER       = STANDARD        | LIFECYCLE          | PART_NUMBER       | JEDEC_TYPE           | DESCRIPTION                                | MANUFTR | MANUF_PN          | RD_CMPLS_LVL | CMPLS_LVL | CLASS | DIP_SMD | FP_ECN           | FROM_PJ       | DATA                             | EE_CHECK_LIST | STATUS | PSL | PREFERENCE | CREATOR | CREATEDAY  ;
{========================================================================================}
 'BZX585-C18/DG'   | 'SMLF'    | 'IC'     | 'BC000C18Z00'(!)  = ''              | ''                 | 'BC000C18Z00'     |'SOD523'| 'DIODE BZX585-C18/DG(75V 200MA SOD523)'    | 'NXP'   | 'BZX585-C18/DG'   | 'EP(V1)'     | ''        | 'IC'  | ''      | ''               | 'S99Q-WIM'    | 'BZX585.pdf'                     | ''            | ''     | ''  | ''         | ''      | '20100429'
 'BZX585-C18/DG'   | 'SMLF'    | 'EMPTY'  | 'BC000C18Z00'(!)  = ''              | ''                 | 'BC000C18Z00'     |'SOD523'| 'DIODE BZX585-C18/DG(75V 200MA SOD523)'    | 'NXP'   | 'BZX585-C18/DG'   | 'EP(V1)'     | ''        | 'IC'  | ''      | ''               | 'S99Q-WIM'    | 'BZX585.pdf'                     | ''            | ''     | ''  | ''         | ''      | '20100429'
 'SMB10J14A'       | 'SMLF'    | 'IC'     | 'BC10J14AZ00'(!)  = ''              | ''                 | 'BC10J14AZ00'     |'D2114'| 'DIODE SMB SMB10J14AHE3/52(14V.1MA.TVS)'   | 'SIL'   | 'SMB10J14AHE3/52' | ''           | 'EP_Tmp'  | 'IC'  | ''      | ''               | 'T96-JAMES'   | 'SIL_SMB10.pdf'                  | ''            | ''     | ''  | ''         | ''      | '20100429'
 'SMB10J14A'       | 'SMLF'    | 'EMPTY'  | 'BC10J14AZ00'(!)  = ''              | ''                 | 'BC10J14AZ00'     |'D2114'| 'DIODE SMB SMB10J14AHE3/52(14V.1MA.TVS)'   | 'SIL'   | 'SMB10J14AHE3/52' | ''           | 'EP_Tmp'  | 'IC'  | ''      | ''               | 'T96-JAMES'   | 'SIL_SMB10.pdf'                  | ''            | ''     | ''  | ''         | ''      | '20100429'
 'SMAJ12A-13-F'    | 'SMLF'    | 'IC'     | 'BCMAJ12AZ00'(!)  = ''              | ''                 | 'BCMAJ12AZ00'     |'D2114'| 'DIODE SMD SMAJ12A-13-F(12V.20.1A.400W)'   | 'DDS'   | 'SMAJ12A-13-F'    | ''           | 'EP_Tmp'  | 'IC'  | ''      | ''               | 'LU1-ROGER'   | 'DDS_SMAJ5(C)A-SMAJ170(C)A.pdf'  | ''            | ''     | ''  | ''         | ''      | '20100429'
 'SMAJ12A-13-F'    | 'SMLF'    | 'EMPTY'  | 'BCMAJ12AZ00'(!)  = ''              | ''                 | 'BCMAJ12AZ00'     |'D2114'| 'DIODE SMD SMAJ12A-13-F(12V.20.1A.400W)'   | 'DDS'   | 'SMAJ12A-13-F'    | ''           | 'EP_Tmp'  | 'IC'  | ''      | ''               | 'LU1-ROGER'   | 'DDS_SMAJ5(C)A-SMAJ170(C)A.pdf'  | ''            | ''     | ''  | ''         | ''      | '20100429'
 'SMAJ13A-13-F'    | 'SMLF'    | 'IC'     | 'BCMAJ13AZ00'(!)  = ''              | ''                 | 'BCMAJ13AZ00'     |'D2010XF'| 'DIODE SMD SMAJ13A-13-F(13V,18.6A,400W)'   | 'DDS'   | 'SMAJ13A-13-F'    | 'EU(V1)'     | 'EU(V1)'  | 'IC'  | ''      | ''               | 'S1M-MARK'    | 'DDS_SMAJ5-0C-A_SMAJ200-C-A.pdf' | ''            | ''     | ''  | ''         | ''      | '20130118'
 'SMAJ13A-13-F'    | 'SMLF'    | 'EMPTY'  | 'BCMAJ13AZ00'(!)  = ''              | ''                 | 'BCMAJ13AZ00'     |'D2010XF'| 'DIODE SMD SMAJ13A-13-F(13V,18.6A,400W)'   | 'DDS'   | 'SMAJ13A-13-F'    | 'EU(V1)'     | 'EU(V1)'  | 'IC'  | ''      | ''               | 'S1M-MARK'    | 'DDS_SMAJ5-0C-A_SMAJ200-C-A.pdf' | ''            | ''     | ''  | ''         | ''      | '20130118'
 'SMAJ18A-13-F'    | 'SMLF'    | 'IC'     | 'BCMAJ18AZ00'(!)  = ''              | ''                 | 'BCMAJ18AZ00'     |'D2010XF'| 'DIODE SMD SMAJ18A-13-F(18V,13.7A,400W)'   | 'DDS'   | 'SMAJ18A-13-F'    | 'EP(V1)'     | ''        | 'IC'  | ''      | ''               | 'S1M-MARK'    | 'DDS_SMAJ5-0C-A_SMAJ200-C-A.pdf' | ''            | ''     | ''  | ''         | ''      | '20121218'
 'SMAJ18A-13-F'    | 'SMLF'    | 'EMPTY'  | 'BCMAJ18AZ00'(!)  = ''              | ''                 | 'BCMAJ18AZ00'     |'D2010XF'| 'DIODE SMD SMAJ18A-13-F(18V,13.7A,400W)'   | 'DDS'   | 'SMAJ18A-13-F'    | 'EP(V1)'     | ''        | 'IC'  | ''      | ''               | 'S1M-MARK'    | 'DDS_SMAJ5-0C-A_SMAJ200-C-A.pdf' | ''            | ''     | ''  | ''         | ''      | '20121218'
 'T3V3S5-7'        | 'SMLF'    | 'IC'     | 'BCT3V3S5Z00'(!)  = ''              | ''                 | 'BCT3V3S5Z00'     |'SOD523XA'| 'DIODE SMD T3V3S5-7(0.9V,10MA)SOD523'      | 'DDS'   | 'T3V3S5-7'        | 'EP(V1)'     | ''        | 'IC'  | ''      | ''               | 'L10-WIN'     | 'DDS_T3V3S5_REV10-2.pdf'         | ''            | ''     | ''  | ''         | ''      | '20140515'
 'T3V3S5-7'        | 'SMLF'    | 'EMPTY'  | 'BCT3V3S5Z00'(!)  = ''              | ''                 | 'BCT3V3S5Z00'     |'SOD523XA'| 'DIODE SMD T3V3S5-7(0.9V,10MA)SOD523'      | 'DDS'   | 'T3V3S5-7'        | 'EP(V1)'     | ''        | 'IC'  | ''      | ''               | 'L10-WIN'     | 'DDS_T3V3S5_REV10-2.pdf'         | ''            | ''     | ''  | ''         | ''      | '20140515'
 'MMSZ5245B'       | 'SMLF'    | 'IC'     | 'BD005245Z00'(!)  = ''              | ''                 | 'BD005245Z00'     |'SOD123XD'| 'DIOIDE ZENER SMD MMSZ5245B(15V,SOD123)'   | 'PJT'   | 'MMSZ5245B'       | 'EP(V1)'     | 'EP(V1)'  | 'IC'  | ''      | ''               | 'JS9-JACK'    | 'PJT_MMSZ5245B-SERIES.pdf'       | ''            | ''     | ''  | ''         | ''      | '20130131'
 'MMSZ5245B'       | 'SMLF'    | 'EMPTY'  | 'BD005245Z00'(!)  = ''              | ''                 | 'BD005245Z00'     |'SOD123XD'| 'DIOIDE ZENER SMD MMSZ5245B(15V,SOD123)'   | 'PJT'   | 'MMSZ5245B'       | 'EP(V1)'     | 'EP(V1)'  | 'IC'  | ''      | ''               | 'JS9-JACK'    | 'PJT_MMSZ5245B-SERIES.pdf'       | ''            | ''     | ''  | ''         | ''      | '20130131'
 'BZT52-B18S'      | 'SMLF'    | 'IC'     | 'BD52B18SZ00'(!)  = ''              | ''                 | 'BD52B18SZ00'     |'SOD323XD'| 'DIODE ZENER SMD BZT52-B18S(17.64V-18.36)' | 'PJT'   | 'BZT52-B18S'      | 'EP(V1)'     | 'EP(V1)'  | 'IC'  | ''      | ''               | 'S1VL-TIM'    | 'PJT_BZT52-B2V4S SERIES.pdf'     | ''            | ''     | ''  | ''         | ''      | '20130820'
 'BZT52-B18S'      | 'SMLF'    | 'EMPTY'  | 'BD52B18SZ00'(!)  = ''              | ''                 | 'BD52B18SZ00'     |'SOD323XD'| 'DIODE ZENER SMD BZT52-B18S(17.64V-18.36)' | 'PJT'   | 'BZT52-B18S'      | 'EP(V1)'     | 'EP(V1)'  | 'IC'  | ''      | ''               | 'S1VL-TIM'    | 'PJT_BZT52-B2V4S SERIES.pdf'     | ''            | ''     | ''  | ''         | ''      | '20130820'
 'BZT52-B5V1S'     | 'SMLF'    | 'IC'     | 'BD52B5V1Z00'(!)  = ''              | ''                 | 'BD52B5V1Z00'     |'SOD323XD'| 'DIODE ZENER SMD BZT52-B5V1S(5.00V-5.20V)' | 'PJT'   | 'BZT52-B5V1S'     | 'EP(V1)'     | 'EP(V1)'  | 'IC'  | ''      | ''               | 'JS9-JACK'    | 'PJT_BZT52-B2V4S SERIES.pdf'     | ''            | ''     | ''  | ''         | ''      | '20130128'
 'BZT52-B5V1S'     | 'SMLF'    | 'EMPTY'  | 'BD52B5V1Z00'(!)  = ''              | ''                 | 'BD52B5V1Z00'     |'SOD323XD'| 'DIODE ZENER SMD BZT52-B5V1S(5.00V-5.20V)' | 'PJT'   | 'BZT52-B5V1S'     | 'EP(V1)'     | 'EP(V1)'  | 'IC'  | ''      | ''               | 'JS9-JACK'    | 'PJT_BZT52-B2V4S SERIES.pdf'     | ''            | ''     | ''  | ''         | ''      | '20130128'
 'BZT52-B6V8S'     | 'SMLF'    | 'IC'     | 'BD52B6V8Z00'(!)  = ''              | ''                 | 'BD52B6V8Z00'     |'SOD323XD'| 'DIODE ZENER SMD BZT52-B6V8S(6.66V-6.94V)' | 'PJT'   | 'BZT52-B6V8S'     | 'EP(V1)'     | ''        | 'IC'  | ''      | ''               | 'JS9-JACK'    | 'PJT_BZT52-B2V4S-SERIES.pdf'     | ''            | ''     | ''  | ''         | ''      | '20130128'
 'BZT52-B6V8S'     | 'SMLF'    | 'EMPTY'  | 'BD52B6V8Z00'(!)  = ''              | ''                 | 'BD52B6V8Z00'     |'SOD323XD'| 'DIODE ZENER SMD BZT52-B6V8S(6.66V-6.94V)' | 'PJT'   | 'BZT52-B6V8S'     | 'EP(V1)'     | ''        | 'IC'  | ''      | ''               | 'JS9-JACK'    | 'PJT_BZT52-B2V4S-SERIES.pdf'     | ''            | ''     | ''  | ''         | ''      | '20130128'
 'BZT52C3V6S-7-F'  | 'SMLF'    | 'IC'     | 'BD52C3V6Z02'(!)  = ''              | ''                 | 'BD52C3V6Z02'     |'SOD323XI'| 'DIODE ZENER SMD BZT52C3V6S-7-F 3.4V~3.8V' | 'DDS'   | 'BZT52C3V6S-7-F'  | 'EP(V1)'     | 'EP(V1)'  | 'IC'  | ''      | ''               | 'T2R-MARK'    | 'DDS_BZT52CXX_REV16-2.pdf'       | ''            | ''     | ''  | ''         | ''      | '20140304'
 'BZT52C3V6S-7-F'  | 'SMLF'    | 'EMPTY'  | 'BD52C3V6Z02'(!)  = ''              | ''                 | 'BD52C3V6Z02'     |'SOD323XI'| 'DIODE ZENER SMD BZT52C3V6S-7-F 3.4V~3.8V' | 'DDS'   | 'BZT52C3V6S-7-F'  | 'EP(V1)'     | 'EP(V1)'  | 'IC'  | ''      | ''               | 'T2R-MARK'    | 'DDS_BZT52CXX_REV16-2.pdf'       | ''            | ''     | ''  | ''         | ''      | '20140304'
 'BZT52C5V6S-7-F'  | 'SMLF'    | 'IC'     | 'BD52C5V6Z03'(!)  = ''              | ''                 | 'BD52C5V6Z03'     |'SOD323XI'| 'DIODE ZENER BZT52C5V6S-7-F(5.6V)SOD323'   | 'DDS'   | 'BZT52C5V6S-7-F'  | 'EP(V1)'     | 'EP(V1)'  | 'IC'  | ''      | ''               | 'T2R-MARK'    | 'DDS_BZT52CXX_REV16-2.pdf'       | ''            | ''     | ''  | ''         | ''      | '20140226'
 'BZT52C5V6S-7-F'  | 'SMLF'    | 'EMPTY'  | 'BD52C5V6Z03'(!)  = ''              | ''                 | 'BD52C5V6Z03'     |'SOD323XI'| 'DIODE ZENER BZT52C5V6S-7-F(5.6V)SOD323'   | 'DDS'   | 'BZT52C5V6S-7-F'  | 'EP(V1)'     | 'EP(V1)'  | 'IC'  | ''      | ''               | 'T2R-MARK'    | 'DDS_BZT52CXX_REV16-2.pdf'       | ''            | ''     | ''  | ''         | ''      | '20140226'
 'TVSS5VESPT'      | 'SMLF'    | 'IC'     | 'BD5VESPTZ00'(!)  = 'End of Design' | 'End of Life'      | 'BD5VESPTZ00'     |'SOD523_EOL'| 'DIODE ZENER SMD TVSS5VESPT(18.6V.9.4A)'   | 'CNK'   | 'TVSS5VESPT'      | ''           | 'EP(V1)'  | 'IC'  | ''      | ''               | 'S99Q-WIM'    | 'CNK_TVSS5VESPT.pdf'             | ''            | ''     | ''  | ''         | ''      | '20100429'
 'TVSS5VESPT'      | 'SMLF'    | 'EMPTY'  | 'BD5VESPTZ00'(!)  = 'End of Design' | 'End of Life'      | 'BD5VESPTZ00'     |'SOD523_EOL'| 'DIODE ZENER SMD TVSS5VESPT(18.6V.9.4A)'   | 'CNK'   | 'TVSS5VESPT'      | ''           | 'EP(V1)'  | 'IC'  | ''      | ''               | 'S99Q-WIM'    | 'CNK_TVSS5VESPT.pdf'             | ''            | ''     | ''  | ''         | ''      | '20100429'
 'SMBT70A'         | 'SMLF'    | 'IC'     | 'BDMBT70AZ00'(!)  = ''              | ''                 | 'BDMBT70AZ00'     |'D2114A'| 'DIODE ZENER SMD SMBT70A-13-F 100V TVS'    | 'DDS'   | 'SMBT70A-13-F'    | ''           | 'EP_Tmp'  | 'IC'  | ''      | ''               | 'S80-WALLACE' | 'SMAT70A-SMBT70A.pdf'            | ''            | ''     | ''  | ''         | ''      | '20100429'
 'SMBT70A'         | 'SMLF'    | 'EMPTY'  | 'BDMBT70AZ00'(!)  = ''              | ''                 | 'BDMBT70AZ00'     |'D2114A'| 'DIODE ZENER SMD SMBT70A-13-F 100V TVS'    | 'DDS'   | 'SMBT70A-13-F'    | ''           | 'EP_Tmp'  | 'IC'  | ''      | ''               | 'S80-WALLACE' | 'SMAT70A-SMBT70A.pdf'            | ''            | ''     | ''  | ''         | ''      | '20100429'
 'SMAZ15-13-F'     | 'SMLF'    | 'IC'     | 'BDSMAZ15Z00'(!)  = ''              | ''                 | 'BDSMAZ15Z00'     |'D2010XF'| 'DIODE ZENER SMD SMAZ15-13-F(14.25~15.7V)' | 'DDS'   | 'SMAZ15-13-F'     | 'EP(V1)'     | ''        | 'IC'  | ''      | ''               | 'JB5-CHINWEI' | 'SMAZ5V1-SMAZ39.pdf'             | ''            | ''     | ''  | ''         | ''      | '20100429'
 'SMAZ15-13-F'     | 'SMLF'    | 'EMPTY'  | 'BDSMAZ15Z00'(!)  = ''              | ''                 | 'BDSMAZ15Z00'     |'D2010XF'| 'DIODE ZENER SMD SMAZ15-13-F(14.25~15.7V)' | 'DDS'   | 'SMAZ15-13-F'     | 'EP(V1)'     | ''        | 'IC'  | ''      | ''               | 'JB5-CHINWEI' | 'SMAZ5V1-SMAZ39.pdf'             | ''            | ''     | ''  | ''         | ''      | '20100429'
 'SMAZ6V8-13-F'    | 'SMLF'    | 'IC'     | 'BDSMAZ6VZ00'(!)  = ''              | ''                 | 'BDSMAZ6VZ00'     |'D2010XF'| 'DIODE ZENER SMD SMAZ6V8-13-F(6.46~7.14V)' | 'DDS'   | 'SMAZ6V8-13-F'    | 'EP(V1)'     | ''        | 'IC'  | ''      | ''               | 'JB5-CHINWEI' | 'SMAZ5V1-SMAZ39.pdf'             | ''            | ''     | ''  | ''         | ''      | '20100429'
 'SMAZ6V8-13-F'    | 'SMLF'    | 'EMPTY'  | 'BDSMAZ6VZ00'(!)  = ''              | ''                 | 'BDSMAZ6VZ00'     |'D2010XF'| 'DIODE ZENER SMD SMAZ6V8-13-F(6.46~7.14V)' | 'DDS'   | 'SMAZ6V8-13-F'    | 'EP(V1)'     | ''        | 'IC'  | ''      | ''               | 'JB5-CHINWEI' | 'SMAZ5V1-SMAZ39.pdf'             | ''            | ''     | ''  | ''         | ''      | '20100429'
 '5.0SMDJ13A'      | 'SMLF'    | 'IC'     | 'BC0MDJ13Z00'(!)  = ''              | ''                 | 'BC0MDJ13Z00'     |'D2723_SMCXC'| 'DIODE SMD 5.0SMDJ13A(13V,233A)DO-214AB'   | 'LFI'   | '5.0SMDJ13A'      | 'EP(V1)'     | ''        | 'IC'  | ''      | ''               | 'UQ3-TOM'     | '5-0SMD SERIES.pdf'              | ''            | ''     | ''  | ''         | ''      | '20140902'
 '5.0SMDJ13A'      | 'SMLF'    | 'EMPTY'  | 'BC0MDJ13Z00'(!)  = ''              | ''                 | 'BC0MDJ13Z00'     |'D2723_SMCXC'| 'DIODE SMD 5.0SMDJ13A(13V,233A)DO-214AB'   | 'LFI'   | '5.0SMDJ13A'      | 'EP(V1)'     | ''        | 'IC'  | ''      | ''               | 'UQ3-TOM'     | '5-0SMD SERIES.pdf'              | ''            | ''     | ''  | ''         | ''      | '20140902'
 'MMSZ5229B'       | 'SMLF'    | 'IC'     | 'BD05229BZ00'(!)  = ''              | ''                 | 'BD05229BZ00'     |'SOD123_2-7X1-6'| 'DIODE ZENER MMSZ5229B(4.3V, 0.5W)'        | 'FAC'   | 'MMSZ5229B'       | 'EP(V1)'     | ''        | 'IC'  | ''      | ''               | 'T6MG-MRAK'   | 'FAC_MMSZ5229B_REV1.1.1.pdf'     | ''            | ''     | ''  | ''         | ''      | '20141223'
 'MMSZ5229B'       | 'SMLF'    | 'EMPTY'  | 'BD05229BZ00'(!)  = ''              | ''                 | 'BD05229BZ00'     |'SOD123_2-7X1-6'| 'DIODE ZENER MMSZ5229B(4.3V, 0.5W)'        | 'FAC'   | 'MMSZ5229B'       | 'EP(V1)'     | ''        | 'IC'  | ''      | ''               | 'T6MG-MRAK'   | 'FAC_MMSZ5229B_REV1.1.1.pdf'     | ''            | ''     | ''  | ''         | ''      | '20141223'
 '5.0SMDJ16A'      | 'SMLF'    | 'IC'     | 'BC0MDJ16Z00'(!)  = ''              | ''                 | 'BC0MDJ16Z00'     |'D2723_SMCXC'| 'DIODE SMD 5.0SMDJ16A(16V,193A,6.5W)'      | 'LFI'   | '5.0SMDJ16A'      | 'EP(V1)'     | ''        | 'IC'  | ''      | ''               | 'T2HV-JOHN'   | 'LFI_5.0SMDJ16A.pdf'             | ''            | ''     | ''  | ''         | ''      | '20151214'
 '5.0SMDJ16A'      | 'SMLF'    | 'EMPTY'  | 'BC0MDJ16Z00'(!)  = ''              | ''                 | 'BC0MDJ16Z00'     |'D2723_SMCXC'| 'DIODE SMD 5.0SMDJ16A(16V,193A,6.5W)'      | 'LFI'   | '5.0SMDJ16A'      | 'EP(V1)'     | ''        | 'IC'  | ''      | ''               | 'T2HV-JOHN'   | 'LFI_5.0SMDJ16A.pdf'             | ''            | ''     | ''  | ''         | ''      | '20151214'
 '5.0SMDJ14A'      | 'SMLF'    | 'IC'     | 'BC0MDJ14000'(!)  = ''              | ''                 | 'BC0MDJ14000'     |'D2723_SMCXC'| 'DIODE SMD 5.0SMDJ14A(14V,216A,5000W)'     | 'LFI'   | '5.0SMDJ14A'      | 'EP(V1)'     | ''        | 'IC'  | ''      | ''               | 'T2HV-JOHN'   | 'LFI_5.0SMDJ14A.pdf'             | ''            | ''     | ''  | ''         | ''      | '20151225'
 '5.0SMDJ14A'      | 'SMLF'    | 'EMPTY'  | 'BC0MDJ14000'(!)  = ''              | ''                 | 'BC0MDJ14000'     |'D2723_SMCXC'| 'DIODE SMD 5.0SMDJ14A(14V,216A,5000W)'     | 'LFI'   | '5.0SMDJ14A'      | 'EP(V1)'     | ''        | 'IC'  | ''      | ''               | 'T2HV-JOHN'   | 'LFI_5.0SMDJ14A.pdf'             | ''            | ''     | ''  | ''         | ''      | '20151225'
 '5.0SMDJ15A'      | 'SMLF'    | 'IC'     | 'BC00015AZ00'(!)  = ''              | ''                 | 'BC00015AZ00'     |'D2723_SMCXC'| 'DIODE SMD 5.0SMDJ15A(15V,205A,5000W)'     | 'LFI'   | '5.0SMDJ15A'      | 'EP(V1)'     | ''        | 'IC'  | ''      | ''               | 'T2HV-MARK'   | 'LFI_5.0SMDJ15A.pdf'             | ''            | ''     | ''  | ''         | ''      | '20160120'
 '5.0SMDJ15A'      | 'SMLF'    | 'EMPTY'  | 'BC00015AZ00'(!)  = ''              | ''                 | 'BC00015AZ00'     |'D2723_SMCXC'| 'DIODE SMD 5.0SMDJ15A(15V,205A,5000W)'     | 'LFI'   | '5.0SMDJ15A'      | 'EP(V1)'     | ''        | 'IC'  | ''      | ''               | 'T2HV-MARK'   | 'LFI_5.0SMDJ15A.pdf'             | ''            | ''     | ''  | ''         | ''      | '20160120'
 'BZT52C3V6SQ-7-F' | 'SMLF'    | 'IC'     | 'BD52C3V6000'(!)  = ''              | ''                 | 'BD52C3V6000'     |'SOD323XI'| 'DIODE ZENER BZT52C3V6SQ-7-F(3.6V,5MA)AEC' | 'DDS'   | 'BZT52C3V6SQ-7-F' | 'EP(V1)'     | ''        | 'IC'  | ''      | ''               | 'T2HV-MARK'   | 'DDS _BZT52C3V6SQ-7-F.pdf'       | ''            | ''     | ''  | ''         | ''      | '20160324'
 'BZT52C3V6SQ-7-F' | 'SMLF'    | 'EMPTY'  | 'BD52C3V6000'(!)  = ''              | ''                 | 'BD52C3V6000'     |'SOD323XI'| 'DIODE ZENER BZT52C3V6SQ-7-F(3.6V,5MA)AEC' | 'DDS'   | 'BZT52C3V6SQ-7-F' | 'EP(V1)'     | ''        | 'IC'  | ''      | ''               | 'T2HV-MARK'   | 'DDS _BZT52C3V6SQ-7-F.pdf'       | ''            | ''     | ''  | ''         | ''      | '20160324'
 'BZT52C3V3LP-7'   | 'SMLF'    | 'IC'     | 'BDC3V3LPZ00'(!)  = ''              | ''                 | 'BDC3V3LPZ00'     |'D0402XA'| 'DIODE ZENER BZT52C3V3LP-7(3.3V,5MA)'      | 'DDS'   | 'BZT52C3V3LP-7'   | 'EP(V1)'     | 'EP(V1)'  | 'IC'  | ''      | ''               | 'JBW-TONY'    | 'DDS_BZT52C3V3LP-7.pdf'          | ''            | ''     | ''  | ''         | ''      | '20170508'
 'BZT52C3V3LP-7'   | 'SMLF'    | 'EMPTY'  | 'BDC3V3LPZ00'(!)  = ''              | ''                 | 'BDC3V3LPZ00'     |'D0402XA'| 'DIODE ZENER BZT52C3V3LP-7(3.3V,5MA)'      | 'DDS'   | 'BZT52C3V3LP-7'   | 'EP(V1)'     | 'EP(V1)'  | 'IC'  | ''      | ''               | 'JBW-TONY'    | 'DDS_BZT52C3V3LP-7.pdf'          | ''            | ''     | ''  | ''         | ''      | '20170508'
 'BZX584C5V6'      | 'SMLF'    | 'IC'     | 'BD584C5VZ00'(!)  = ''              | ''                 | 'BD584C5VZ00'     |'SOD523_1-2X0-8XB'| 'DIODE ZENER BZX584C5V6(5.6V,5MA)SOD-523)' | 'PJT'   | 'BZX584C5V6'      | 'EP'         | 'EP'      | 'IC'  | ''      | ''               | 'F09-SEAN'    | 'PJT_BZX584C5V6.pdf'             | ''            | ''     | ''  | ''         | ''      | '20170929'
 'BZX584C5V6'      | 'SMLF'    | 'EMPTY'  | 'BD584C5VZ00'(!)  = ''              | ''                 | 'BD584C5VZ00'     |'SOD523_1-2X0-8XB'| 'DIODE ZENER BZX584C5V6(5.6V,5MA)SOD-523)' | 'PJT'   | 'BZX584C5V6'      | 'EP'         | 'EP'      | 'IC'  | ''      | ''               | 'F09-SEAN'    | 'PJT_BZX584C5V6.pdf'             | ''            | ''     | ''  | ''         | ''      | '20170929'
 '1SMC13AT3G'      | 'SMLF'    | 'IC'     | 'BD1SMC13Z00'(!)  = ''              | ''                 | 'BD1SMC13Z00'     |'D2723_SMCXJ'| 'DIODE ZENER SMD 1SMC13AT3G(13V,0.75W)'    | 'ONS'   | '1SMC13AT3G'      | 'EP(V1)'     | ''        | 'IC'  | ''      | ''               | 'F09-SEAN'    | 'ONS_1SMC13AT3G.pdf'             | ''            | ''     | ''  | ''         | ''      | '20171020'
 '1SMC13AT3G'      | 'SMLF'    | 'EMPTY'  | 'BD1SMC13Z00'(!)  = ''              | ''                 | 'BD1SMC13Z00'     |'D2723_SMCXJ'| 'DIODE ZENER SMD 1SMC13AT3G(13V,0.75W)'    | 'ONS'   | '1SMC13AT3G'      | 'EP(V1)'     | ''        | 'IC'  | ''      | ''               | 'F09-SEAN'    | 'ONS_1SMC13AT3G.pdf'             | ''            | ''     | ''  | ''         | ''      | '20171020'
 'MMSZ5229BT1G'    | 'SMLF'    | 'IC'     | 'BD005229Z00'(!)  = ''              | ''                 | 'BD005229Z00'     |'SOD123XE'| 'DIODE ZENER MMSZ5229BT1G(4.3V,0.5W)'      | 'ONS'   | 'MMSZ5229BT1G'    | 'EP(V1)'     | ''        | 'IC'  | ''      | ''               | 'S6V-JW'      | 'ONS_MMSZ5229BT1G.pdf'           | ''            | ''     | ''  | ''         | ''      | '20180910'
 'MMSZ5229BT1G'    | 'SMLF'    | 'EMPTY'  | 'BD005229Z00'(!)  = ''              | ''                 | 'BD005229Z00'     |'SOD123XE'| 'DIODE ZENER MMSZ5229BT1G(4.3V,0.5W)'      | 'ONS'   | 'MMSZ5229BT1G'    | 'EP(V1)'     | ''        | 'IC'  | ''      | ''               | 'S6V-JW'      | 'ONS_MMSZ5229BT1G.pdf'           | ''            | ''     | ''  | ''         | ''      | '20180910'
 'PDZ3.3B'         | 'SMLF'    | 'IC'     | 'BDPDZ33BZ01'(!)  = ''              | ''                 | 'BDPDZ33BZ01'     |'SOD323F_H44'| 'DIODE ZENER SMD PDZ3.3B(3.32V-3.53V)'     | 'PHI'   | 'PDZ3.3B'         | 'EP(V1)'     | 'EP(V1)'  | 'IC'  | ''      | ''               | 'JG5-TOM'     | 'PHI_PDZ3.3B.pdf'                | ''            | ''     | ''  | ''         | ''      | '20181105'
 'PDZ3.3B'         | 'SMLF'    | 'EMPTY'  | 'BDPDZ33BZ01'(!)  = ''              | ''                 | 'BDPDZ33BZ01'     |'SOD323F_H44'| 'DIODE ZENER SMD PDZ3.3B(3.32V-3.53V)'     | 'PHI'   | 'PDZ3.3B'         | 'EP(V1)'     | 'EP(V1)'  | 'IC'  | ''      | ''               | 'JG5-TOM'     | 'PHI_PDZ3.3B.pdf'                | ''            | ''     | ''  | ''         | ''      | '20181105'
 'BZX884-C4V7'     | 'SMLF'    | 'IC'     | 'BD84C4V7Z00'(!)  = ''              | ''                 | 'BD84C4V7Z00'     |'SOD882_0-985X0-585'| 'DIODE ZENER BZX884(4.47-4.95V,0.2A,0.25W' | 'NXE'   | 'BZX884-C4V7'     | 'EP(V1)'     | 'EP(V1)'  | 'IC'  | ''      | ''               | 'S5U-JOANNE'  | 'NXE_BZX884-C4V7.pdf'            | ''            | ''     | ''  | ''         | ''      | '20190119'
 'BZX884-C4V7'     | 'SMLF'    | 'EMPTY'  | 'BD84C4V7Z00'(!)  = ''              | ''                 | 'BD84C4V7Z00'     |'SOD882_0-985X0-585'| 'DIODE ZENER BZX884(4.47-4.95V,0.2A,0.25W' | 'NXE'   | 'BZX884-C4V7'     | 'EP(V1)'     | 'EP(V1)'  | 'IC'  | ''      | ''               | 'S5U-JOANNE'  | 'NXE_BZX884-C4V7.pdf'            | ''            | ''     | ''  | ''         | ''      | '20190119'
 'BZX384-C12'      | 'SMLF'    | 'IC'     | 'BC384C12Z00'(!)  = ''              | ''                 | 'BC384C12Z00'     |'SOD323F_H44'| 'DIODE SMD BZX384-C12(0.9V,0.25A,0.3W)'    | 'NXE'   | 'BZX384-C12'      | 'EP(V1)'     | ''        | 'IC'  | ''      | ''               | 'BAICELL-MJ'  | 'NXE_BZX384-C12.pdf'             | ''            | ''     | ''  | ''         | ''      | '20190129'
 'BZX384-C12'      | 'SMLF'    | 'EMPTY'  | 'BC384C12Z00'(!)  = ''              | ''                 | 'BC384C12Z00'     |'SOD323F_H44'| 'DIODE SMD BZX384-C12(0.9V,0.25A,0.3W)'    | 'NXE'   | 'BZX384-C12'      | 'EP(V1)'     | ''        | 'IC'  | ''      | ''               | 'BAICELL-MJ'  | 'NXE_BZX384-C12.pdf'             | ''            | ''     | ''  | ''         | ''      | '20190129'
 'MMSZ3V9T1G'      | 'SMLF'    | 'IC'     | 'BD03V9T1000'(!)  = ''              | ''                 | 'BD03V9T1000'     |'SOD123XE'| 'DIODE ZENER MMSZ3V9T1G(3.9V,0.5W)'        | 'ONS'   | 'MMSZ3V9T1G'      | 'EP(V1)'     | ''        | 'IC'  | ''      | ''               | 'F09-JANE'    | 'ONS_MMSZ3V9T1G.pdf'             | ''            | ''     | ''  | ''         | ''      | '20180308'
 'MMSZ3V9T1G'      | 'SMLF'    | 'EMPTY'  | 'BD03V9T1000'(!)  = ''              | ''                 | 'BD03V9T1000'     |'SOD123XE'| 'DIODE ZENER MMSZ3V9T1G(3.9V,0.5W)'        | 'ONS'   | 'MMSZ3V9T1G'      | 'EP(V1)'     | ''        | 'IC'  | ''      | ''               | 'F09-JANE'    | 'ONS_MMSZ3V9T1G.pdf'             | ''            | ''     | ''  | ''         | ''      | '20180308'
 'MMSZ5230B-7-F'   | 'SMLF'    | 'IC'     | 'BD005230Z01'(!)  = ''              | ''                 | 'BD005230Z01'     |'SOD123_2-7X1-55XA'| 'DIODE ZENER SMD MMSZ5230B(4.7V,SOD123)'   | 'DDS'   | 'MMSZ5230B-7-F'   | 'EP(V1)'     | 'EP(V1)'  | 'IC'  | ''      | ''               | 'S8I-LEO'     | 'DDS_MMSZ5230B-7-F.pdf'          | ''            | ''     | ''  | ''         | ''      | '20190925'
 'MMSZ5230B-7-F'   | 'SMLF'    | 'EMPTY'  | 'BD005230Z01'(!)  = ''              | ''                 | 'BD005230Z01'     |'SOD123_2-7X1-55XA'| 'DIODE ZENER SMD MMSZ5230B(4.7V,SOD123)'   | 'DDS'   | 'MMSZ5230B-7-F'   | 'EP(V1)'     | 'EP(V1)'  | 'IC'  | ''      | ''               | 'S8I-LEO'     | 'DDS_MMSZ5230B-7-F.pdf'          | ''            | ''     | ''  | ''         | ''      | '20190925'
 'BZT52-B12S'      | 'SMLF'    | 'IC'     | 'BD52B12SZ00'(!)  = ''              | ''                 | 'BD52B12SZ00'     |'SOD323_1-85X1-25'| 'DIODE ZENER SMD BZT52-B12S(11.76-12.24V)' | 'PJT'   | 'BZT52-B12S'      | 'EP(V1)'     | 'EP(V1)'  | 'IC'  | ''      | ''               | 'S8A-JAY'     | 'PJT_BZT52-B12S.pdf'             | ''            | ''     | ''  | ''         | ''      | '20200324'
 'BZT52-B12S'      | 'SMLF'    | 'EMPTY'  | 'BD52B12SZ00'(!)  = ''              | ''                 | 'BD52B12SZ00'     |'SOD323_1-85X1-25'| 'DIODE ZENER SMD BZT52-B12S(11.76-12.24V)' | 'PJT'   | 'BZT52-B12S'      | 'EP(V1)'     | 'EP(V1)'  | 'IC'  | ''      | ''               | 'S8A-JAY'     | 'PJT_BZT52-B12S.pdf'             | ''            | ''     | ''  | ''         | ''      | '20200324'
 'BZT52-B3V6S'     | 'SMLF'    | 'IC'     | 'BD2B3V6SZ00'(!)  = ''              | ''                 | 'BD2B3V6SZ00'     |'SOD323_1-85X1-25XA'| 'DIODE ZENER SMD BZT52-B3V6S(3.6V,5MA)'    | 'PJT'   | 'BZT52-B3V6S'     | 'EP(V1)'     | 'EP(V1)'  | 'IC'  | ''      | ''               | 'S5Z-WILLIAM' | 'PJT_BZT52-B3V6S.pdf'            | ''            | ''     | ''  | ''         | ''      | '20200504'
 'BZT52-B3V6S'     | 'SMLF'    | 'EMPTY'  | 'BD2B3V6SZ00'(!)  = ''              | ''                 | 'BD2B3V6SZ00'     |'SOD323_1-85X1-25XA'| 'DIODE ZENER SMD BZT52-B3V6S(3.6V,5MA)'    | 'PJT'   | 'BZT52-B3V6S'     | 'EP(V1)'     | 'EP(V1)'  | 'IC'  | ''      | ''               | 'S5Z-WILLIAM' | 'PJT_BZT52-B3V6S.pdf'            | ''            | ''     | ''  | ''         | ''      | '20200504'
 'MM3Z12VT1G'      | 'SMLF'    | 'IC'     | 'BD12VT1GZ00'(!)  = ''              | ''                 | 'BD12VT1GZ00'     |'SOD323XH'| 'DIODE ZENER MM3Z12VT1G (12V,SOD323)'      | 'ONS'   | 'MM3Z12VT1G'      | 'EP(V1)'     | ''        | 'IC'  | ''      | ''               | 'S8A-YC'      | 'ONS_MM3Z12VT1G.pdf'             | ''            | ''     | ''  | ''         | ''      | '20200610'
 'MM3Z12VT1G'      | 'SMLF'    | 'EMPTY'  | 'BD12VT1GZ00'(!)  = ''              | ''                 | 'BD12VT1GZ00'     |'SOD323XH'| 'DIODE ZENER MM3Z12VT1G (12V,SOD323)'      | 'ONS'   | 'MM3Z12VT1G'      | 'EP(V1)'     | ''        | 'IC'  | ''      | ''               | 'S8A-YC'      | 'ONS_MM3Z12VT1G.pdf'             | ''            | ''     | ''  | ''         | ''      | '20200610'
 'PDZ12B'          | 'SMLF'    | 'IC'     | 'BDPDZ12BZ00'(!)  = ''              | ''                 | 'BDPDZ12BZ00'     |'SOD323F_H44'| 'DIODE ZENER SMD PDZ12B(11.74V-12.24V)AEC' | 'NXE'   | 'PDZ12B'          | 'EU(V1)'     | ''        | 'IC'  | ''      | ''               | 'S8A-YC'      | 'NXE_PDZ12B.pdf'                 | ''            | ''     | ''  | ''         | ''      | '20200610'
 'PDZ12B'          | 'SMLF'    | 'EMPTY'  | 'BDPDZ12BZ00'(!)  = ''              | ''                 | 'BDPDZ12BZ00'     |'SOD323F_H44'| 'DIODE ZENER SMD PDZ12B(11.74V-12.24V)AEC' | 'NXE'   | 'PDZ12B'          | 'EU(V1)'     | ''        | 'IC'  | ''      | ''               | 'S8A-YC'      | 'NXE_PDZ12B.pdf'                 | ''            | ''     | ''  | ''         | ''      | '20200610'
 'BZT52C24S'       | 'SMLF'    | 'IC'     | 'BD52C24SZ00'(!)  = ''              | ''                 | 'BD52C24SZ00'     |'SOD323XI'| 'DIODE ZENER SMD BZT52C24S(24V 5MA)'       | 'DDS'   | 'BZT52C24S'       | 'EP(V1)'     | ''        | 'IC'  | ''      | ''               | 'P0A-STEVE'   | 'DDS_BZT52C24S.pdf'              | ''            | ''     | ''  | ''         | ''      | '20210311'
 'BZT52C24S'       | 'SMLF'    | 'EMPTY'  | 'BD52C24SZ00'(!)  = ''              | ''                 | 'BD52C24SZ00'     |'SOD323XI'| 'DIODE ZENER SMD BZT52C24S(24V 5MA)'       | 'DDS'   | 'BZT52C24S'       | 'EP(V1)'     | ''        | 'IC'  | ''      | ''               | 'P0A-STEVE'   | 'DDS_BZT52C24S.pdf'              | ''            | ''     | ''  | ''         | ''      | '20210311'
 'MMSZ5230BT1G'    | 'SMLF'    | 'IC'     | 'BD5230BTZ00'(!)  = ''              | ''                 | 'BD5230BTZ00'     |'SOD123XE'| 'DIODE ZENER MMSZ5230BT1G(4.7V,0.02A,0.5W' | 'ONS'   | 'MMSZ5230BT1G'    | 'EP(V1)'     | 'EP(V1)'  | 'IC'  | ''      | ''               | 'S8I-ANSON'   | 'ONS_MMSZ5230BT1G.pdf'           | ''            | ''     | ''  | ''         | ''      | '20210816'
 'MMSZ5230BT1G'    | 'SMLF'    | 'EMPTY'  | 'BD5230BTZ00'(!)  = ''              | ''                 | 'BD5230BTZ00'     |'SOD123XE'| 'DIODE ZENER MMSZ5230BT1G(4.7V,0.02A,0.5W' | 'ONS'   | 'MMSZ5230BT1G'    | 'EP(V1)'     | 'EP(V1)'  | 'IC'  | ''      | ''               | 'S8I-ANSON'   | 'ONS_MMSZ5230BT1G.pdf'           | ''            | ''     | ''  | ''         | ''      | '20210816'
 'MMSZ5252BS-7-F'  | 'SMLF'    | 'IC'     | 'BD005252Z00'(!)  = ''              | ''                 | 'BD005252Z00'     |'SOD323_1-7X1-3XA'| 'DIODE ZENER MMSZ5252BS-7-F(24V,SOD-323)'  | 'DDS'   | 'MMSZ5252BS-7-F'  | 'EP(V1)'     | ''        | 'IC'  | ''      | ''               | 'MF6-DANNY'   | 'DDS_MMSZ5252BS-7-F.pdf'         | ''            | ''     | ''  | ''         | ''      | '20230222'
 'MMSZ5252BS-7-F'  | 'SMLF'    | 'EMPTY'  | 'BD005252Z00'(!)  = ''              | ''                 | 'BD005252Z00'     |'SOD323_1-7X1-3XA'| 'DIODE ZENER MMSZ5252BS-7-F(24V,SOD-323)'  | 'DDS'   | 'MMSZ5252BS-7-F'  | 'EP(V1)'     | ''        | 'IC'  | ''      | ''               | 'MF6-DANNY'   | 'DDS_MMSZ5252BS-7-F.pdf'         | ''            | ''     | ''  | ''         | ''      | '20230222'
 'MMSZ5230BT1G'    | 'SMLF'    | 'IC'     | 'BD5230BTZ00SEL1'(!) = ''              | ''               | 'BD5230BTZ00SEL1' |'SOD123XE'| 'DIODEZEN MMSZ5230BT1G(4.7V0.02A0.5W)SELA' | 'ONS'   | 'MMSZ5230BT1G'    | 'EP(V1)'     | 'EP(V1)'  | 'IC'  | ''      | 'SEL_15QPN.xlsx' | 'S8I-ANSON'   | 'ONS_MMSZ5230BT1G.pdf'           | ''            | ''     | ''  | ''         | ''      | '20230628'
 'MMSZ5230BT1G'    | 'SMLF'    | 'EMPTY'  | 'BD5230BTZ00SEL1'(!) = ''              | ''               | 'BD5230BTZ00SEL1' |'SOD123XE'| 'DIODEZEN MMSZ5230BT1G(4.7V0.02A0.5W)SELA' | 'ONS'   | 'MMSZ5230BT1G'    | 'EP(V1)'     | 'EP(V1)'  | 'IC'  | ''      | 'SEL_15QPN.xlsx' | 'S8I-ANSON'   | 'ONS_MMSZ5230BT1G.pdf'           | ''            | ''     | ''  | ''         | ''      | '20230628'
 'BZT52-B12S'      | 'SMLF'    | 'IC'     | 'BD52B12SZ00SEL1'(!) = ''              | ''               | 'BD52B12SZ00SEL1' |'SOD323_1-85X1-25'| 'DIODEZENSMD BZT52-B12S(11.76-12.24V)SELA' | 'PJT'   | 'BZT52-B12S'      | 'EP(V1)'     | 'EP(V1)'  | 'IC'  | ''      | 'SEL_15QPN.xlsx' | 'S8A-JAY'     | 'PJT_BZT52-B12S.pdf'             | ''            | ''     | ''  | ''         | ''      | '20230628'
 'BZT52-B12S'      | 'SMLF'    | 'EMPTY'  | 'BD52B12SZ00SEL1'(!) = ''              | ''               | 'BD52B12SZ00SEL1' |'SOD323_1-85X1-25'| 'DIODEZENSMD BZT52-B12S(11.76-12.24V)SELA' | 'PJT'   | 'BZT52-B12S'      | 'EP(V1)'     | 'EP(V1)'  | 'IC'  | ''      | 'SEL_15QPN.xlsx' | 'S8A-JAY'     | 'PJT_BZT52-B12S.pdf'             | ''            | ''     | ''  | ''         | ''      | '20230628'

END_PART

END.

